G04*
G04 #@! TF.GenerationSoftware,Altium Limited,Altium Designer,23.0.1 (38)*
G04*
G04 Layer_Color=16711935*
%FSLAX25Y25*%
%MOIN*%
G70*
G04*
G04 #@! TF.SameCoordinates,C48E81DB-6E20-4E2D-80E6-7C5AFAA1A21F*
G04*
G04*
G04 #@! TF.FilePolarity,Positive*
G04*
G01*
G75*
%ADD16C,0.00394*%
D16*
X148622Y-372195D02*
G03*
X134252Y-372195I-7185J0D01*
G01*
X200197Y-385876D02*
G03*
X192717Y-385876I-3740J0D01*
G01*
X200197D02*
G03*
X192717Y-385876I-3740J0D01*
G01*
X148622Y-372195D02*
G03*
X134252Y-372195I-7185J0D01*
G01*
X283661Y-365009D02*
X700787D01*
X-28543Y22392D02*
X700787D01*
X700787Y-365009D01*
X-28543Y-397490D02*
Y22392D01*
Y-397490D02*
X30512D01*
Y-365009D01*
X102756D01*
Y-397490D02*
Y-365009D01*
Y-397490D02*
X134252D01*
Y-372195D01*
X148622Y-413238D02*
Y-372195D01*
X150591Y-415206D02*
X190748D01*
X202165D02*
X281693D01*
X283661Y-413238D02*
Y-365009D01*
X148622Y-413238D02*
X150591Y-415206D01*
X190748D02*
X192717Y-413238D01*
X200197D02*
X202165Y-415206D01*
X281693D02*
X283661Y-413238D01*
X192717D02*
Y-385876D01*
X200197Y-413238D02*
Y-385876D01*
M02*
